(kicad_pcb
	(version 20260206)
	(generator "pcbnew")
	(generator_version "10.0")
	(general
		(thickness 1.6)
		(legacy_teardrops no)
	)
	(paper "A4")
	(title_block
		(title "Bryce Canyon_R.DPB_16317-1_OCP.brd")
		(comment 1 "Bryce Canyon / footprints 894-897 of 2099")
	)
	(layers
		(0 "F.Cu" signal "TOP")
		(4 "In1.Cu" signal "L2GND")
		(6 "In2.Cu" signal "L3")
		(8 "In3.Cu" signal "L4VCC")
		(10 "In4.Cu" signal "L5VCC")
		(12 "In5.Cu" signal "L6")
		(14 "In6.Cu" signal "L7GND")
		(2 "B.Cu" signal "BOTTOM")
		(9 "F.Adhes" user "F.Adhesive")
		(11 "B.Adhes" user "B.Adhesive")
		(13 "F.Paste" user "Package Geometry/Pastemask Top")
		(15 "B.Paste" user "Package Geometry/Pastemask Bottom")
		(5 "F.SilkS" user "Ref Des/Silkscreen Top")
		(7 "B.SilkS" user "Ref Des/Silkscreen Bottom")
		(1 "F.Mask" user "Board Geometry/Soldermask Top")
		(3 "B.Mask" user "Board Geometry/Soldermask Bottom")
		(17 "Dwgs.User" user "User.Drawings")
		(19 "Cmts.User" user "User.Comments")
		(21 "Eco1.User" user "User.Eco1")
		(23 "Eco2.User" user "User.Eco2")
		(25 "Edge.Cuts" user "Board Geometry/Outline")
		(27 "Margin" user)
		(31 "F.CrtYd" user "Package Geometry/Place Bound Top")
		(29 "B.CrtYd" user "Package Geometry/Place Bound Bottom")
		(35 "F.Fab" user "Ref Des/Assembly Top")
		(33 "B.Fab" user "Ref Des/Assembly Bottom")
	)
	(footprint ""
		(layer "F.Cu")
		(at 262.46201 -226.715574)
		(property "Reference" "R170"
			(at 0 0 0)
			(layer "F.SilkS")
			(hide yes)
			(effects
				(font
					(size 1.27 1.27)
				)
			)
		)
		(property "Value" "16K2R2F-GP"
			(at 0.064008 -3.993896 0)
			(unlocked yes)
			(layer "F.Fab")
			(hide yes)
			(effects
				(font
					(size 1.016 1.016)
					(thickness 0.1524)
				)
			)
		)
		(property "Device Type" "R402H16"
			(at 0.064008 -5.517896 0)
			(unlocked yes)
			(layer "F.Fab")
			(hide yes)
			(effects
				(font
					(size 1.016 1.016)
					(thickness 0.1524)
				)
			)
		)
		(duplicate_pad_numbers_are_jumpers no)
		(fp_line
			(start -0.508 -0.9398)
			(end -0.508 0.9398)
			(stroke
				(width 0.1524)
				(type default)
			)
			(layer "F.SilkS")
		)
		(fp_line
			(start 0.508 -0.9398)
			(end -0.508 -0.9398)
			(stroke
				(width 0.1524)
				(type default)
			)
			(layer "F.SilkS")
		)
		(fp_rect
			(start -0.508 0.9398)
			(end 0.508 -0.9398)
			(stroke
				(width 0)
				(type default)
			)
			(fill no)
			(layer "F.CrtYd")
		)
		(fp_rect
			(start -0.508 0.9398)
			(end 0.508 -0.9398)
			(stroke
				(width 0)
				(type default)
			)
			(fill no)
			(layer "F.Fab")
		)
		(pad "1" smd custom
			(at 0 -0.4445)
			(size 0.1397 0.1397)
			(layers "F.Cu" "F.Mask" "F.Paste")
			(net "P5V_B_4")
			(options
				(clearance outline)
				(anchor circle)
			)
			(primitives
				(gr_poly
					(pts
						(arc
							(start -0.1778 -0.2794)
							(mid -0.249642 -0.249642)
							(end -0.2794 -0.1778)
						)
						(arc
							(start -0.2794 0.1778)
							(mid -0.249642 0.249642)
							(end -0.1778 0.2794)
						)
						(arc
							(start 0.1778 0.2794)
							(mid 0.249642 0.249642)
							(end 0.2794 0.1778)
						)
						(arc
							(start 0.2794 -0.1778)
							(mid 0.249642 -0.249642)
							(end 0.1778 -0.2794)
						)
					)
					(width 0)
					(fill yes)
				)
			)
		)
		(pad "2" smd custom
			(at 0 0.4445)
			(size 0.1397 0.1397)
			(layers "F.Cu" "F.Mask" "F.Paste")
			(net "P5V_B_4_SENSE")
			(options
				(clearance outline)
				(anchor circle)
			)
			(primitives
				(gr_poly
					(pts
						(arc
							(start -0.1778 -0.2794)
							(mid -0.249642 -0.249642)
							(end -0.2794 -0.1778)
						)
						(arc
							(start -0.2794 0.1778)
							(mid -0.249642 0.249642)
							(end -0.1778 0.2794)
						)
						(arc
							(start 0.1778 0.2794)
							(mid 0.249642 0.249642)
							(end 0.2794 0.1778)
						)
						(arc
							(start 0.2794 -0.1778)
							(mid 0.249642 -0.249642)
							(end 0.1778 -0.2794)
						)
					)
					(width 0)
					(fill yes)
				)
			)
		)
	)
	(footprint ""
		(layer "F.Cu")
		(at 257.331972 -342.338406 90)
		(property "Reference" "Q202"
			(at 0 0 90)
			(layer "F.SilkS")
			(hide yes)
			(effects
				(font
					(size 1.27 1.27)
				)
			)
		)
		(property "Value" "IRFH8201TRPBF-GP"
			(at -4.2164 -4.3688 90)
			(unlocked yes)
			(layer "F.Fab")
			(hide yes)
			(effects
				(font
					(size 1.016 1.016)
					(thickness 0.1524)
				)
			)
		)
		(property "Device Type" "PPAK-5PH42"
			(at -4.2164 -5.8928 90)
			(unlocked yes)
			(layer "F.Fab")
			(hide yes)
			(effects
				(font
					(size 1.016 1.016)
					(thickness 0.1524)
				)
			)
		)
		(duplicate_pad_numbers_are_jumpers no)
		(fp_line
			(start 2.8956 -2.794)
			(end 2.8956 4.826)
			(stroke
				(width 0.1524)
				(type default)
			)
			(layer "F.SilkS")
		)
		(fp_line
			(start -2.8956 -2.794)
			(end 2.8956 -2.794)
			(stroke
				(width 0.1524)
				(type default)
			)
			(layer "F.SilkS")
		)
		(fp_line
			(start 2.8956 4.826)
			(end -2.8956 4.826)
			(stroke
				(width 0.1524)
				(type default)
			)
			(layer "F.SilkS")
		)
		(fp_line
			(start -2.8956 4.826)
			(end -2.8956 -2.794)
			(stroke
				(width 0.1524)
				(type default)
			)
			(layer "F.SilkS")
		)
		(fp_line
			(start -1.9431 4.9276)
			(end -3.0353 4.9276)
			(stroke
				(width 0.3302)
				(type default)
			)
			(layer "F.SilkS")
		)
		(fp_line
			(start -3.0353 4.9276)
			(end -3.0353 3.9624)
			(stroke
				(width 0.3302)
				(type default)
			)
			(layer "F.SilkS")
		)
		(fp_poly
			(pts
				(xy -2.3622 5.334) (xy -1.4986 5.334) (xy -1.9304 4.9022)
			)
			(stroke
				(width 0)
				(type default)
			)
			(fill yes)
			(layer "F.SilkS")
		)
		(fp_poly
			(pts
				(xy 0.3556 -0.3556) (xy 2.6416 -0.3556) (xy 2.6416 -2.54) (xy 0.3556 -2.54)
			)
			(stroke
				(width 0)
				(type default)
			)
			(fill yes)
			(layer "F.Paste")
		)
		(fp_poly
			(pts
				(xy -2.6416 -0.3556) (xy -0.3556 -0.3556) (xy -0.3556 -2.54) (xy -2.6416 -2.54)
			)
			(stroke
				(width 0)
				(type default)
			)
			(fill yes)
			(layer "F.Paste")
		)
		(fp_poly
			(pts
				(xy 0.3556 2.54) (xy 2.6416 2.54) (xy 2.6416 0.3556) (xy 0.3556 0.3556)
			)
			(stroke
				(width 0)
				(type default)
			)
			(fill yes)
			(layer "F.Paste")
		)
		(fp_poly
			(pts
				(xy -2.6416 2.54) (xy -0.3556 2.54) (xy -0.3556 0.3556) (xy -2.6416 0.3556)
			)
			(stroke
				(width 0)
				(type default)
			)
			(fill yes)
			(layer "F.Paste")
		)
		(fp_rect
			(start -2.5781 3.9878)
			(end 2.5781 -2.1082)
			(stroke
				(width 0)
				(type default)
			)
			(fill no)
			(layer "F.CrtYd")
		)
		(fp_poly
			(pts
				(xy -3.1496 5.08) (xy -3.1496 -3.048) (xy 3.1496 -3.048) (xy 3.1496 3.9751) (xy 2.5781 3.9751) (xy 2.5781 -2.1082)
				(xy -2.5781 -2.1082) (xy -2.5781 3.9878) (xy 3.1496 3.9878) (xy 3.1496 5.08)
			)
			(stroke
				(width 0)
				(type default)
			)
			(fill no)
			(layer "F.CrtYd")
		)
		(fp_rect
			(start -3.1496 5.08)
			(end 3.1496 -3.048)
			(stroke
				(width 0)
				(type default)
			)
			(fill no)
			(layer "F.Fab")
		)
		(pad "1" smd rect
			(at -1.905 3.81 90)
			(size 0.762 1.524)
			(layers "F.Cu" "F.Mask" "F.Paste")
			(net "P12V_B")
		)
		(pad "2" smd rect
			(at -0.635 3.81 90)
			(size 0.762 1.524)
			(layers "F.Cu" "F.Mask" "F.Paste")
			(net "P12V_B")
		)
		(pad "3" smd rect
			(at 0.635 3.81 90)
			(size 0.762 1.524)
			(layers "F.Cu" "F.Mask" "F.Paste")
			(net "P12V_B")
		)
		(pad "4" smd rect
			(at 1.905 3.81 90)
			(size 0.762 1.524)
			(layers "F.Cu" "F.Mask" "F.Paste")
			(net "MB3_12V_CTRL_GATE2")
		)
		(pad "5" smd rect
			(at 0 0 90)
			(size 5.2832 5.08)
			(layers "F.Cu" "F.Mask" "F.Paste")
			(net "MB3_P12V_IN_R")
		)
		(pad "6" smd rect
			(at 0.635 -2.032 90)
			(size 0.0254 0.0254)
			(layers "F.Cu" "F.Mask" "F.Paste")
			(net "MB3_P12V_IN_R")
		)
		(pad "7" smd rect
			(at -0.635 -2.032 90)
			(size 0.0254 0.0254)
			(layers "F.Cu" "F.Mask" "F.Paste")
			(net "MB3_P12V_IN_R")
		)
		(pad "8" smd rect
			(at -1.905 -2.032 90)
			(size 0.0254 0.0254)
			(layers "F.Cu" "F.Mask" "F.Paste")
			(net "MB3_P12V_IN_R")
		)
	)
	(footprint ""
		(layer "F.Cu")
		(at 470.662 -129.286 180)
		(property "Reference" "R607"
			(at 0 0 180)
			(layer "F.SilkS")
			(hide yes)
			(effects
				(font
					(size 1.27 1.27)
				)
			)
		)
		(property "Value" "1KR2F-3-GP"
			(at 0.064008 -3.993896 180)
			(unlocked yes)
			(layer "F.Fab")
			(hide yes)
			(effects
				(font
					(size 1.016 1.016)
					(thickness 0.1524)
				)
			)
		)
		(property "Device Type" "R402H16"
			(at 0.064008 -5.517896 180)
			(unlocked yes)
			(layer "F.Fab")
			(hide yes)
			(effects
				(font
					(size 1.016 1.016)
					(thickness 0.1524)
				)
			)
		)
		(duplicate_pad_numbers_are_jumpers no)
		(fp_line
			(start 0.508 -0.9398)
			(end -0.508 -0.9398)
			(stroke
				(width 0.1524)
				(type default)
			)
			(layer "F.SilkS")
		)
		(fp_line
			(start -0.508 -0.9398)
			(end -0.508 0.9398)
			(stroke
				(width 0.1524)
				(type default)
			)
			(layer "F.SilkS")
		)
		(fp_rect
			(start -0.508 0.9398)
			(end 0.508 -0.9398)
			(stroke
				(width 0)
				(type default)
			)
			(fill no)
			(layer "F.CrtYd")
		)
		(fp_rect
			(start -0.508 0.9398)
			(end 0.508 -0.9398)
			(stroke
				(width 0)
				(type default)
			)
			(fill no)
			(layer "F.Fab")
		)
		(pad "1" smd custom
			(at 0 -0.4445 180)
			(size 0.1397 0.1397)
			(layers "F.Cu" "F.Mask" "F.Paste")
			(net "P3V3_STBY_B")
			(options
				(clearance outline)
				(anchor circle)
			)
			(primitives
				(gr_poly
					(pts
						(arc
							(start -0.1778 -0.2794)
							(mid -0.249642 -0.249642)
							(end -0.2794 -0.1778)
						)
						(arc
							(start -0.2794 0.1778)
							(mid -0.249642 0.249642)
							(end -0.1778 0.2794)
						)
						(arc
							(start 0.1778 0.2794)
							(mid 0.249642 0.249642)
							(end 0.2794 0.1778)
						)
						(arc
							(start 0.2794 -0.1778)
							(mid 0.249642 -0.249642)
							(end 0.1778 -0.2794)
						)
					)
					(width 0)
					(fill yes)
				)
			)
		)
		(pad "2" smd custom
			(at 0 0.4445 180)
			(size 0.1397 0.1397)
			(layers "F.Cu" "F.Mask" "F.Paste")
			(net "SW_PWR_R_HDD23")
			(options
				(clearance outline)
				(anchor circle)
			)
			(primitives
				(gr_poly
					(pts
						(arc
							(start -0.1778 -0.2794)
							(mid -0.249642 -0.249642)
							(end -0.2794 -0.1778)
						)
						(arc
							(start -0.2794 0.1778)
							(mid -0.249642 0.249642)
							(end -0.1778 0.2794)
						)
						(arc
							(start 0.1778 0.2794)
							(mid 0.249642 0.249642)
							(end 0.2794 0.1778)
						)
						(arc
							(start 0.2794 -0.1778)
							(mid 0.249642 -0.249642)
							(end 0.1778 -0.2794)
						)
					)
					(width 0)
					(fill yes)
				)
			)
		)
	)
	(footprint ""
		(layer "F.Cu")
		(at 243.078 -306.705)
		(property "Reference" "U30"
			(at 0 0 0)
			(layer "F.SilkS")
			(hide yes)
			(effects
				(font
					(size 1.27 1.27)
				)
			)
		)
		(property "Value" "MAX31790ATI-T-GP"
			(at 4.1021 -3.7338 0)
			(unlocked yes)
			(layer "F.Fab")
			(hide yes)
			(effects
				(font
					(size 1.016 1.016)
					(thickness 0.1524)
				)
			)
		)
		(property "Device Type" "QFN28-G2D7H32"
			(at 4.1021 -5.2578 0)
			(unlocked yes)
			(layer "F.Fab")
			(hide yes)
			(effects
				(font
					(size 1.016 1.016)
					(thickness 0.1524)
				)
			)
		)
		(duplicate_pad_numbers_are_jumpers no)
		(fp_line
			(start -3.0099 -3.0099)
			(end -1.7399 -3.0099)
			(stroke
				(width 0.1524)
				(type default)
			)
			(layer "F.SilkS")
		)
		(fp_line
			(start -3.0099 -1.7399)
			(end -3.0099 -3.0099)
			(stroke
				(width 0.1524)
				(type default)
			)
			(layer "F.SilkS")
		)
		(fp_line
			(start -3.0099 1.7399)
			(end -3.0099 3.0099)
			(stroke
				(width 0.1524)
				(type default)
			)
			(layer "F.SilkS")
		)
		(fp_line
			(start -3.0099 3.0099)
			(end -1.7399 3.0099)
			(stroke
				(width 0.1524)
				(type default)
			)
			(layer "F.SilkS")
		)
		(fp_line
			(start -2.7813 -0.4064)
			(end -3.5433 -0.4064)
			(stroke
				(width 0.1524)
				(type default)
			)
			(layer "F.SilkS")
		)
		(fp_line
			(start -1.1938 2.7813)
			(end -1.1938 3.2893)
			(stroke
				(width 0.1524)
				(type default)
			)
			(layer "F.SilkS")
		)
		(fp_line
			(start -0.4064 -2.7813)
			(end -0.4064 -3.2893)
			(stroke
				(width 0.1524)
				(type default)
			)
			(layer "F.SilkS")
		)
		(fp_line
			(start 0.8128 2.7813)
			(end 0.8128 3.5433)
			(stroke
				(width 0.1524)
				(type default)
			)
			(layer "F.SilkS")
		)
		(fp_line
			(start 1.7399 3.0099)
			(end 3.0099 3.0099)
			(stroke
				(width 0.1524)
				(type default)
			)
			(layer "F.SilkS")
		)
		(fp_line
			(start 2.7813 0)
			(end 3.2893 0)
			(stroke
				(width 0.1524)
				(type default)
			)
			(layer "F.SilkS")
		)
		(fp_line
			(start 3.0099 3.0099)
			(end 3.0099 1.7399)
			(stroke
				(width 0.1524)
				(type default)
			)
			(layer "F.SilkS")
		)
		(fp_poly
			(pts
				(xy 3.0099 -1.7399) (xy 1.7399 -3.0099) (xy 3.0099 -3.0099)
			)
			(stroke
				(width 0)
				(type default)
			)
			(fill yes)
			(layer "F.SilkS")
		)
		(fp_rect
			(start -1.9939 1.9939)
			(end 1.9939 -1.9939)
			(stroke
				(width 0)
				(type default)
			)
			(fill no)
			(layer "F.CrtYd")
		)
		(fp_poly
			(pts
				(xy -3.0099 3.0099) (xy -3.0099 -3.0099) (xy 3.0099 -3.0099) (xy 3.0099 3.0099) (xy -1.98882 3.0099)
				(xy -1.98882 1.9939) (xy 1.9939 1.9939) (xy 1.9939 -1.9939) (xy -1.9939 -1.9939) (xy -1.9939 3.0099)
			)
			(stroke
				(width 0)
				(type default)
			)
			(fill no)
			(layer "F.CrtYd")
		)
		(fp_rect
			(start -3.0099 3.0099)
			(end 3.0099 -3.0099)
			(stroke
				(width 0)
				(type default)
			)
			(fill no)
			(layer "F.Fab")
		)
		(pad "1" smd rect
			(at 1.199896 -2.032)
			(size 0.2032 0.9398)
			(layers "F.Cu" "F.Mask" "F.Paste")
			(net "MAX31790_A_FREQ_ST")
		)
		(pad "2" smd rect
			(at 0.8001 -2.032)
			(size 0.2032 0.9398)
			(layers "F.Cu" "F.Mask" "F.Paste")
			(net "MAX31790_A_SPIN_ST")
		)
		(pad "3" smd rect
			(at 0.40005 -2.032)
			(size 0.2032 0.9398)
			(layers "F.Cu" "F.Mask" "F.Paste")
			(net "MAX31790_A_ADD1")
		)
		(pad "4" smd rect
			(at 0 -2.032)
			(size 0.2032 0.9398)
			(layers "F.Cu" "F.Mask" "F.Paste")
			(net "MAX31790_A_ADD0")
		)
		(pad "5" smd rect
			(at -0.40005 -2.032)
			(size 0.2032 0.9398)
			(layers "F.Cu" "F.Mask" "F.Paste")
			(net "MAX31790_A_WD_ST")
		)
		(pad "6" smd rect
			(at -0.8001 -2.032)
			(size 0.2032 0.9398)
			(layers "F.Cu" "F.Mask" "F.Paste")
			(net "Net_311")
		)
		(pad "7" smd rect
			(at -1.199896 -2.032)
			(size 0.2032 0.9398)
			(layers "F.Cu" "F.Mask" "F.Paste")
			(net "GND")
		)
		(pad "8" smd rect
			(at -2.032 -1.199896)
			(size 0.9398 0.2032)
			(layers "F.Cu" "F.Mask" "F.Paste")
			(net "GND")
		)
		(pad "9" smd rect
			(at -2.032 -0.8001)
			(size 0.9398 0.2032)
			(layers "F.Cu" "F.Mask" "F.Paste")
			(net "FANTACH_A_R3")
		)
		(pad "10" smd rect
			(at -2.032 -0.40005)
			(size 0.9398 0.2032)
			(layers "F.Cu" "F.Mask" "F.Paste")
			(net "Net_314")
		)
		(pad "11" smd rect
			(at -2.032 0)
			(size 0.9398 0.2032)
			(layers "F.Cu" "F.Mask" "F.Paste")
			(net "FANTACH_A_F3")
		)
		(pad "12" smd rect
			(at -2.032 0.40005)
			(size 0.9398 0.2032)
			(layers "F.Cu" "F.Mask" "F.Paste")
			(net "Net_315")
		)
		(pad "13" smd rect
			(at -2.032 0.8001)
			(size 0.9398 0.2032)
			(layers "F.Cu" "F.Mask" "F.Paste")
			(net "FANTACH_A_R2")
		)
		(pad "14" smd rect
			(at -2.032 1.199896)
			(size 0.9398 0.2032)
			(layers "F.Cu" "F.Mask" "F.Paste")
			(net "Net_316")
		)
		(pad "15" smd rect
			(at -1.199896 2.032)
			(size 0.2032 0.9398)
			(layers "F.Cu" "F.Mask" "F.Paste")
			(net "FANTACH_A_F2")
		)
		(pad "16" smd rect
			(at -0.8001 2.032)
			(size 0.2032 0.9398)
			(layers "F.Cu" "F.Mask" "F.Paste")
			(net "Net_313")
		)
		(pad "17" smd rect
			(at -0.40005 2.032)
			(size 0.2032 0.9398)
			(layers "F.Cu" "F.Mask" "F.Paste")
			(net "FANTACH_A_R1")
		)
		(pad "18" smd rect
			(at 0 2.032)
			(size 0.2032 0.9398)
			(layers "F.Cu" "F.Mask" "F.Paste")
			(net "FANTACH_A_R0")
		)
		(pad "19" smd rect
			(at 0.40005 2.032)
			(size 0.2032 0.9398)
			(layers "F.Cu" "F.Mask" "F.Paste")
			(net "FANTACH_A_F1")
		)
		(pad "20" smd rect
			(at 0.8001 2.032)
			(size 0.2032 0.9398)
			(layers "F.Cu" "F.Mask" "F.Paste")
			(net "FANTACH_A_F0")
		)
		(pad "21" smd rect
			(at 1.199896 2.032)
			(size 0.2032 0.9398)
			(layers "F.Cu" "F.Mask" "F.Paste")
			(net "P3V3_STBY_A")
		)
		(pad "22" smd rect
			(at 2.032 1.199896)
			(size 0.9398 0.2032)
			(layers "F.Cu" "F.Mask" "F.Paste")
			(net "MAX31790_A_SDA")
		)
		(pad "23" smd rect
			(at 2.032 0.8001)
			(size 0.9398 0.2032)
			(layers "F.Cu" "F.Mask" "F.Paste")
			(net "MAX31790_A_SCL")
		)
		(pad "24" smd rect
			(at 2.032 0.40005)
			(size 0.9398 0.2032)
			(layers "F.Cu" "F.Mask" "F.Paste")
			(net "MAX31790_A_FAIL")
		)
		(pad "25" smd rect
			(at 2.032 0)
			(size 0.9398 0.2032)
			(layers "F.Cu" "F.Mask" "F.Paste")
			(net "MAX31790_A_PWM_ST0")
		)
		(pad "26" smd rect
			(at 2.032 -0.40005)
			(size 0.9398 0.2032)
			(layers "F.Cu" "F.Mask" "F.Paste")
			(net "MAX31790_A_PWM_ST1")
		)
		(pad "27" smd rect
			(at 2.032 -0.8001)
			(size 0.9398 0.2032)
			(layers "F.Cu" "F.Mask" "F.Paste")
			(net "MAX31790_A_FULL_SPEED")
		)
		(pad "28" smd rect
			(at 2.032 -1.199896)
			(size 0.9398 0.2032)
			(layers "F.Cu" "F.Mask" "F.Paste")
			(net "Net_312")
		)
		(pad "29" smd rect
			(at 0 0)
			(size 2.6924 2.6924)
			(layers "F.Cu" "F.Mask" "F.Paste")
			(net "GND")
		)
	)
)
